FILE_TYPE=LIBRARY_PARTS;
primitive 'SCONN11_9192031111LF';
  pin
    '1':
      PIN_NUMBER='(1)';
      BIDIRECTIONAL='TRUE';
      INPUT_LOAD='(-0.01,0.01)';
      OUTPUT_LOAD='(1.0,-1.0)';
    '3':
      PIN_NUMBER='(3)';
      BIDIRECTIONAL='TRUE';
      INPUT_LOAD='(-0.01,0.01)';
      OUTPUT_LOAD='(1.0,-1.0)';
    '4':
      PIN_NUMBER='(4)';
      BIDIRECTIONAL='TRUE';
      INPUT_LOAD='(-0.01,0.01)';
      OUTPUT_LOAD='(1.0,-1.0)';
    '5':
      PIN_NUMBER='(5)';
      BIDIRECTIONAL='TRUE';
      INPUT_LOAD='(-0.01,0.01)';
      OUTPUT_LOAD='(1.0,-1.0)';
    '2':
      PIN_NUMBER='(2)';
      BIDIRECTIONAL='TRUE';
      INPUT_LOAD='(-0.01,0.01)';
      OUTPUT_LOAD='(1.0,-1.0)';
    'G1':
      PIN_NUMBER='(G1)';
      PINUSE='POWER';
      NO_LOAD_CHECK='Both';
      NO_IO_CHECK='Both';
      NO_ASSERT_CHECK='TRUE';
      NO_DIR_CHECK='TRUE';
      ALLOW_CONNECT='TRUE';
    'G2':
      PIN_NUMBER='(G2)';
      PINUSE='POWER';
      NO_LOAD_CHECK='Both';
      NO_IO_CHECK='Both';
      NO_ASSERT_CHECK='TRUE';
      NO_DIR_CHECK='TRUE';
      ALLOW_CONNECT='TRUE';
    '6':
      PIN_NUMBER='(6)';
      BIDIRECTIONAL='TRUE';
      INPUT_LOAD='(-0.01,0.01)';
      OUTPUT_LOAD='(1.0,-1.0)';
    '7':
      PIN_NUMBER='(7)';
      BIDIRECTIONAL='TRUE';
      INPUT_LOAD='(-0.01,0.01)';
      OUTPUT_LOAD='(1.0,-1.0)';
    '8':
      PIN_NUMBER='(8)';
      BIDIRECTIONAL='TRUE';
      INPUT_LOAD='(-0.01,0.01)';
      OUTPUT_LOAD='(1.0,-1.0)';
    '9':
      PIN_NUMBER='(9)';
      BIDIRECTIONAL='TRUE';
      INPUT_LOAD='(-0.01,0.01)';
      OUTPUT_LOAD='(1.0,-1.0)';
    '10':
      PIN_NUMBER='(10)';
      BIDIRECTIONAL='TRUE';
      INPUT_LOAD='(-0.01,0.01)';
      OUTPUT_LOAD='(1.0,-1.0)';
    '11':
      PIN_NUMBER='(11)';
      BIDIRECTIONAL='TRUE';
      INPUT_LOAD='(-0.01,0.01)';
      OUTPUT_LOAD='(1.0,-1.0)';
  end_pin;
  body
    PART_NAME='SCONN11_9192031111LF';
    BODY_NAME='SCONN11_9192031111LF';
    PHYS_DES_PREFIX='J';
    CLASS='IO';
  end_body;
end_primitive;

END.
